# T6G (Grand Teton) — schematic netlist excerpt (pin names and nets, part order shuffled) for the footprints in the layout excerpt that follows; sources: Cadence DE-HDL packaged netlist, KiCad conversion of 04192023_DAF0TMB3IC0_F0TG_MB_C_brd_V02_OCP.brd

C2234  Q_CAP  22UF 4V 20% X6S  pkg C0402  page 69 : A = PVDDCR_CPU1_P0 ; B = GND
R386  Q_RES  15 1% CHIP  pkg 0402LF  page 21 : A = M_L_CPU0_ALERT_N ; B = M_L_CPU0_ALERT_R_N

(kicad_pcb
	(version 20260206)
	(generator "pcbnew")
	(generator_version "10.0")
	(general
		(thickness 1.6)
		(legacy_teardrops no)
	)
	(paper "A4")
	(title_block
		(title "04192023_DAF0TMB3IC0_F0TG_MB_C_brd_V02_OCP.brd")
		(comment 1 "Grand Teton / footprints 7367-7368 of 8354")
	)
	(layers
		(0 "F.Cu" signal "TOP")
		(4 "In1.Cu" signal "GND")
		(6 "In2.Cu" signal "IN1")
		(8 "In3.Cu" signal "GND1")
		(10 "In4.Cu" signal "IN2")
		(12 "In5.Cu" signal "GND2")
		(14 "In6.Cu" signal "IN3")
		(16 "In7.Cu" signal "GND3")
		(18 "In8.Cu" signal "VCC")
		(20 "In9.Cu" signal "VCC1")
		(22 "In10.Cu" signal "GND4")
		(24 "In11.Cu" signal "IN4")
		(26 "In12.Cu" signal "GND5")
		(28 "In13.Cu" signal "IN5")
		(30 "In14.Cu" signal "GND6")
		(32 "In15.Cu" signal "IN6")
		(34 "In16.Cu" signal "GND7")
		(2 "B.Cu" signal "BOTTOM")
		(9 "F.Adhes" user "F.Adhesive")
		(11 "B.Adhes" user "B.Adhesive")
		(13 "F.Paste" user "Package Geometry/Pastemask Top")
		(15 "B.Paste" user "Package Geometry/Pastemask Bottom")
		(5 "F.SilkS" user "Ref Des/Silkscreen Top")
		(7 "B.SilkS" user "Ref Des/Silkscreen Bottom")
		(1 "F.Mask" user "Board Geometry/Soldermask Top")
		(3 "B.Mask" user "Board Geometry/Soldermask Bottom")
		(17 "Dwgs.User" user "User.Drawings")
		(19 "Cmts.User" user "User.Comments")
		(21 "Eco1.User" user "User.Eco1")
		(23 "Eco2.User" user "User.Eco2")
		(25 "Edge.Cuts" user "Board Geometry/Outline")
		(27 "Margin" user)
		(31 "F.CrtYd" user "Package Geometry/Place Bound Top")
		(29 "B.CrtYd" user "Package Geometry/Place Bound Bottom")
		(35 "F.Fab" user "Ref Des/Assembly Top")
		(33 "B.Fab" user "Ref Des/Assembly Bottom")
	)
	(footprint ""
		(layer "B.Cu")
		(at 453.191118 -244.08511)
		(property "Reference" "R386"
			(at 0 0 0)
			(layer "B.SilkS")
			(hide yes)
			(effects
				(font
					(size 1.27 1.27)
				)
				(justify mirror)
			)
		)
		(property "Value" ""
			(at 0 0 0)
			(layer "B.Fab")
			(effects
				(font
					(size 1.27 1.27)
				)
				(justify mirror)
			)
		)
		(duplicate_pad_numbers_are_jumpers no)
		(fp_line
			(start -0.7874 -0.4064)
			(end -0.7874 0.4064)
			(stroke
				(width 0.1524)
				(type default)
			)
			(layer "B.SilkS")
		)
		(fp_line
			(start -0.7874 0.4064)
			(end 0.7874 0.4064)
			(stroke
				(width 0.1524)
				(type default)
			)
			(layer "B.SilkS")
		)
		(fp_line
			(start 0.7874 -0.4064)
			(end -0.7874 -0.4064)
			(stroke
				(width 0.1524)
				(type default)
			)
			(layer "B.SilkS")
		)
		(fp_line
			(start 0.7874 0.4064)
			(end 0.7874 -0.4064)
			(stroke
				(width 0.1524)
				(type default)
			)
			(layer "B.SilkS")
		)
		(fp_line
			(start -0.67945 -0.3048)
			(end -0.67945 0.3048)
			(stroke
				(width 0.1)
				(type default)
			)
			(layer "B.Fab")
		)
		(fp_line
			(start -0.67945 0.3048)
			(end -0.120396 0.3048)
			(stroke
				(width 0.1)
				(type default)
			)
			(layer "B.Fab")
		)
		(fp_line
			(start -0.12065 -0.3048)
			(end -0.67945 -0.3048)
			(stroke
				(width 0.1)
				(type default)
			)
			(layer "B.Fab")
		)
		(fp_line
			(start -0.12065 -0.2794)
			(end -0.12065 -0.3048)
			(stroke
				(width 0.1)
				(type default)
			)
			(layer "B.Fab")
		)
		(fp_line
			(start -0.120396 0.2794)
			(end 0.12065 0.2794)
			(stroke
				(width 0.1)
				(type default)
			)
			(layer "B.Fab")
		)
		(fp_line
			(start -0.120396 0.3048)
			(end -0.120396 0.2794)
			(stroke
				(width 0.1)
				(type default)
			)
			(layer "B.Fab")
		)
		(fp_line
			(start 0.12065 -0.305054)
			(end 0.12065 -0.2794)
			(stroke
				(width 0.1)
				(type default)
			)
			(layer "B.Fab")
		)
		(fp_line
			(start 0.12065 -0.2794)
			(end -0.12065 -0.2794)
			(stroke
				(width 0.1)
				(type default)
			)
			(layer "B.Fab")
		)
		(fp_line
			(start 0.12065 0.2794)
			(end 0.12065 0.3048)
			(stroke
				(width 0.1)
				(type default)
			)
			(layer "B.Fab")
		)
		(fp_line
			(start 0.12065 0.3048)
			(end 0.67945 0.3048)
			(stroke
				(width 0.1)
				(type default)
			)
			(layer "B.Fab")
		)
		(fp_line
			(start 0.67945 -0.305054)
			(end 0.12065 -0.305054)
			(stroke
				(width 0.1)
				(type default)
			)
			(layer "B.Fab")
		)
		(fp_line
			(start 0.67945 0.3048)
			(end 0.67945 -0.305054)
			(stroke
				(width 0.1)
				(type default)
			)
			(layer "B.Fab")
		)
		(pad "1" smd circle
			(at 0.40005 0 180)
			(size 0 0)
			(layers "B.Cu" "B.Mask" "B.Paste")
			(net "M_L_CPU0_ALERT_N")
		)
		(pad "2" smd circle
			(at -0.40005 0 180)
			(size 0 0)
			(layers "B.Cu" "B.Mask" "B.Paste")
			(net "M_L_CPU0_ALERT_R_N")
		)
	)
	(footprint ""
		(layer "B.Cu")
		(at 349.675958 -272.284952 180)
		(property "Reference" "C2234"
			(at 0 0 0)
			(layer "B.SilkS")
			(hide yes)
			(effects
				(font
					(size 1.27 1.27)
				)
				(justify mirror)
			)
		)
		(property "Value" ""
			(at 0 0 0)
			(layer "B.Fab")
			(effects
				(font
					(size 1.27 1.27)
				)
				(justify mirror)
			)
		)
		(duplicate_pad_numbers_are_jumpers no)
		(fp_line
			(start 0.7874 0.4064)
			(end 0.7874 -0.4064)
			(stroke
				(width 0.1524)
				(type default)
			)
			(layer "B.SilkS")
		)
		(fp_line
			(start 0.7874 -0.4064)
			(end -0.7874 -0.4064)
			(stroke
				(width 0.1524)
				(type default)
			)
			(layer "B.SilkS")
		)
		(fp_line
			(start -0.7874 0.4064)
			(end 0.7874 0.4064)
			(stroke
				(width 0.1524)
				(type default)
			)
			(layer "B.SilkS")
		)
		(fp_line
			(start -0.7874 -0.4064)
			(end -0.7874 0.4064)
			(stroke
				(width 0.1524)
				(type default)
			)
			(layer "B.SilkS")
		)
		(fp_line
			(start 0.67945 0.3048)
			(end 0.67945 -0.305054)
			(stroke
				(width 0.1)
				(type default)
			)
			(layer "B.Fab")
		)
		(fp_line
			(start 0.67945 -0.305054)
			(end 0.12065 -0.305054)
			(stroke
				(width 0.1)
				(type default)
			)
			(layer "B.Fab")
		)
		(fp_line
			(start 0.12065 0.3048)
			(end 0.67945 0.3048)
			(stroke
				(width 0.1)
				(type default)
			)
			(layer "B.Fab")
		)
		(fp_line
			(start 0.12065 0.2794)
			(end 0.12065 0.3048)
			(stroke
				(width 0.1)
				(type default)
			)
			(layer "B.Fab")
		)
		(fp_line
			(start 0.12065 -0.2794)
			(end -0.12065 -0.2794)
			(stroke
				(width 0.1)
				(type default)
			)
			(layer "B.Fab")
		)
		(fp_line
			(start 0.12065 -0.305054)
			(end 0.12065 -0.2794)
			(stroke
				(width 0.1)
				(type default)
			)
			(layer "B.Fab")
		)
		(fp_line
			(start -0.120396 0.3048)
			(end -0.120396 0.2794)
			(stroke
				(width 0.1)
				(type default)
			)
			(layer "B.Fab")
		)
		(fp_line
			(start -0.120396 0.2794)
			(end 0.12065 0.2794)
			(stroke
				(width 0.1)
				(type default)
			)
			(layer "B.Fab")
		)
		(fp_line
			(start -0.12065 -0.2794)
			(end -0.12065 -0.3048)
			(stroke
				(width 0.1)
				(type default)
			)
			(layer "B.Fab")
		)
		(fp_line
			(start -0.12065 -0.3048)
			(end -0.67945 -0.3048)
			(stroke
				(width 0.1)
				(type default)
			)
			(layer "B.Fab")
		)
		(fp_line
			(start -0.67945 0.3048)
			(end -0.120396 0.3048)
			(stroke
				(width 0.1)
				(type default)
			)
			(layer "B.Fab")
		)
		(fp_line
			(start -0.67945 -0.3048)
			(end -0.67945 0.3048)
			(stroke
				(width 0.1)
				(type default)
			)
			(layer "B.Fab")
		)
		(pad "1" smd circle
			(at 0.40005 0)
			(size 0 0)
			(layers "B.Cu" "B.Mask" "B.Paste")
			(net "PVDDCR_CPU1_P0")
		)
		(pad "2" smd circle
			(at -0.40005 0)
			(size 0 0)
			(layers "B.Cu" "B.Mask" "B.Paste")
			(net "GND")
		)
	)
)
